(kicad_pcb
	(version 20260206)
	(generator "pcbnew")
	(generator_version "10.0")
	(general
		(thickness 1.6)
		(legacy_teardrops no)
	)
	(paper "A4")
	(title_block
		(title "01162023_DA0F0TEBIF0_F0T_Expander_BD_F_brd_V02_OCP.brd")
		(comment 1 "Grand Teton / footprints 6377-6384 of 9728")
	)
	(layers
		(0 "F.Cu" signal "TOP")
		(4 "In1.Cu" signal "GND")
		(6 "In2.Cu" signal "VCC")
		(8 "In3.Cu" signal "VCC1")
		(10 "In4.Cu" signal "GND1")
		(12 "In5.Cu" signal "IN1")
		(14 "In6.Cu" signal "GND2")
		(16 "In7.Cu" signal "IN2")
		(18 "In8.Cu" signal "GND3")
		(20 "In9.Cu" signal "IN3")
		(22 "In10.Cu" signal "GND4")
		(24 "In11.Cu" signal "IN4")
		(26 "In12.Cu" signal "GND5")
		(28 "In13.Cu" signal "IN5")
		(30 "In14.Cu" signal "GND6")
		(32 "In15.Cu" signal "IN6")
		(34 "In16.Cu" signal "GND7")
		(2 "B.Cu" signal "BOTTOM")
		(9 "F.Adhes" user "F.Adhesive")
		(11 "B.Adhes" user "B.Adhesive")
		(13 "F.Paste" user "Package Geometry/Pastemask Top")
		(15 "B.Paste" user "Package Geometry/Pastemask Bottom")
		(5 "F.SilkS" user "Ref Des/Silkscreen Top")
		(7 "B.SilkS" user "Ref Des/Silkscreen Bottom")
		(1 "F.Mask" user "Board Geometry/Soldermask Top")
		(3 "B.Mask" user "Board Geometry/Soldermask Bottom")
		(17 "Dwgs.User" user "User.Drawings")
		(19 "Cmts.User" user "User.Comments")
		(21 "Eco1.User" user "User.Eco1")
		(23 "Eco2.User" user "User.Eco2")
		(25 "Edge.Cuts" user "Board Geometry/Outline")
		(27 "Margin" user)
		(31 "F.CrtYd" user "Package Geometry/Place Bound Top")
		(29 "B.CrtYd" user "Package Geometry/Place Bound Bottom")
		(35 "F.Fab" user "Ref Des/Assembly Top")
		(33 "B.Fab" user "Ref Des/Assembly Bottom")
	)
	(footprint ""
		(layer "F.Cu")
		(at 173.394116 -34.248852)
		(property "Reference" "R5675"
			(at 0 0 0)
			(layer "F.SilkS")
			(hide yes)
			(effects
				(font
					(size 1.27 1.27)
				)
			)
		)
		(property "Value" ""
			(at 0 0 0)
			(layer "F.Fab")
			(effects
				(font
					(size 1.27 1.27)
				)
			)
		)
		(duplicate_pad_numbers_are_jumpers no)
		(fp_line
			(start -0.7874 -0.4064)
			(end 0.7874 -0.4064)
			(stroke
				(width 0.1524)
				(type default)
			)
			(layer "F.SilkS")
		)
		(fp_line
			(start -0.7874 0.4064)
			(end -0.7874 -0.4064)
			(stroke
				(width 0.1524)
				(type default)
			)
			(layer "F.SilkS")
		)
		(fp_line
			(start 0.7874 -0.4064)
			(end 0.7874 0.4064)
			(stroke
				(width 0.1524)
				(type default)
			)
			(layer "F.SilkS")
		)
		(fp_line
			(start 0.7874 0.4064)
			(end -0.7874 0.4064)
			(stroke
				(width 0.1524)
				(type default)
			)
			(layer "F.SilkS")
		)
		(fp_line
			(start -0.67945 -0.305054)
			(end -0.12065 -0.305054)
			(stroke
				(width 0.1)
				(type default)
			)
			(layer "F.Fab")
		)
		(fp_line
			(start -0.67945 0.3048)
			(end -0.67945 -0.305054)
			(stroke
				(width 0.1)
				(type default)
			)
			(layer "F.Fab")
		)
		(fp_line
			(start -0.12065 -0.305054)
			(end -0.12065 -0.2794)
			(stroke
				(width 0.1)
				(type default)
			)
			(layer "F.Fab")
		)
		(fp_line
			(start -0.12065 -0.2794)
			(end 0.12065 -0.2794)
			(stroke
				(width 0.1)
				(type default)
			)
			(layer "F.Fab")
		)
		(fp_line
			(start -0.12065 0.2794)
			(end -0.12065 0.3048)
			(stroke
				(width 0.1)
				(type default)
			)
			(layer "F.Fab")
		)
		(fp_line
			(start -0.12065 0.3048)
			(end -0.67945 0.3048)
			(stroke
				(width 0.1)
				(type default)
			)
			(layer "F.Fab")
		)
		(fp_line
			(start 0.120396 0.2794)
			(end -0.12065 0.2794)
			(stroke
				(width 0.1)
				(type default)
			)
			(layer "F.Fab")
		)
		(fp_line
			(start 0.120396 0.3048)
			(end 0.120396 0.2794)
			(stroke
				(width 0.1)
				(type default)
			)
			(layer "F.Fab")
		)
		(fp_line
			(start 0.12065 -0.3048)
			(end 0.67945 -0.3048)
			(stroke
				(width 0.1)
				(type default)
			)
			(layer "F.Fab")
		)
		(fp_line
			(start 0.12065 -0.2794)
			(end 0.12065 -0.3048)
			(stroke
				(width 0.1)
				(type default)
			)
			(layer "F.Fab")
		)
		(fp_line
			(start 0.67945 -0.3048)
			(end 0.67945 0.3048)
			(stroke
				(width 0.1)
				(type default)
			)
			(layer "F.Fab")
		)
		(fp_line
			(start 0.67945 0.3048)
			(end 0.120396 0.3048)
			(stroke
				(width 0.1)
				(type default)
			)
			(layer "F.Fab")
		)
		(pad "1" smd circle
			(at -0.40005 0)
			(size 0 0)
			(layers "F.Cu" "F.Mask" "F.Paste")
			(net "RST_SMB_SSD6_ISO_N")
		)
		(pad "2" smd circle
			(at 0.40005 0)
			(size 0 0)
			(layers "F.Cu" "F.Mask" "F.Paste")
			(net "P3V3_SSD6")
		)
	)
	(footprint ""
		(layer "F.Cu")
		(at 235.619544 -149.752812 180)
		(property "Reference" "R1211"
			(at 0 0 180)
			(layer "F.SilkS")
			(hide yes)
			(effects
				(font
					(size 1.27 1.27)
				)
			)
		)
		(property "Value" ""
			(at 0 0 180)
			(layer "F.Fab")
			(effects
				(font
					(size 1.27 1.27)
				)
			)
		)
		(duplicate_pad_numbers_are_jumpers no)
		(fp_line
			(start 0.7874 0.4064)
			(end -0.7874 0.4064)
			(stroke
				(width 0.1524)
				(type default)
			)
			(layer "F.SilkS")
		)
		(fp_line
			(start 0.67945 0.3048)
			(end 0.120396 0.3048)
			(stroke
				(width 0.1)
				(type default)
			)
			(layer "F.Fab")
		)
		(fp_line
			(start 0.67945 -0.3048)
			(end 0.67945 0.3048)
			(stroke
				(width 0.1)
				(type default)
			)
			(layer "F.Fab")
		)
		(fp_line
			(start 0.12065 -0.2794)
			(end 0.12065 -0.3048)
			(stroke
				(width 0.1)
				(type default)
			)
			(layer "F.Fab")
		)
		(fp_line
			(start 0.12065 -0.3048)
			(end 0.67945 -0.3048)
			(stroke
				(width 0.1)
				(type default)
			)
			(layer "F.Fab")
		)
		(fp_line
			(start 0.120396 0.3048)
			(end 0.120396 0.2794)
			(stroke
				(width 0.1)
				(type default)
			)
			(layer "F.Fab")
		)
		(fp_line
			(start 0.120396 0.2794)
			(end -0.12065 0.2794)
			(stroke
				(width 0.1)
				(type default)
			)
			(layer "F.Fab")
		)
		(fp_line
			(start -0.12065 0.3048)
			(end -0.67945 0.3048)
			(stroke
				(width 0.1)
				(type default)
			)
			(layer "F.Fab")
		)
		(fp_line
			(start -0.12065 0.2794)
			(end -0.12065 0.3048)
			(stroke
				(width 0.1)
				(type default)
			)
			(layer "F.Fab")
		)
		(fp_line
			(start -0.12065 -0.2794)
			(end 0.12065 -0.2794)
			(stroke
				(width 0.1)
				(type default)
			)
			(layer "F.Fab")
		)
		(fp_line
			(start -0.12065 -0.305054)
			(end -0.12065 -0.2794)
			(stroke
				(width 0.1)
				(type default)
			)
			(layer "F.Fab")
		)
		(fp_line
			(start -0.67945 0.3048)
			(end -0.67945 -0.305054)
			(stroke
				(width 0.1)
				(type default)
			)
			(layer "F.Fab")
		)
		(fp_line
			(start -0.67945 -0.305054)
			(end -0.12065 -0.305054)
			(stroke
				(width 0.1)
				(type default)
			)
			(layer "F.Fab")
		)
		(pad "1" smd circle
			(at -0.40005 0 180)
			(size 0 0)
			(layers "F.Cu" "F.Mask" "F.Paste")
			(net "CLK_100M_PEX3_REF_R_DP")
		)
		(pad "2" smd circle
			(at 0.40005 0 180)
			(size 0 0)
			(layers "F.Cu" "F.Mask" "F.Paste")
			(net "CLK_100M_PEX3_REF_DP")
		)
	)
	(footprint ""
		(layer "F.Cu")
		(at 230.153718 -273.063716 90)
		(property "Reference" "C4294"
			(at 0 0 90)
			(layer "F.SilkS")
			(hide yes)
			(effects
				(font
					(size 1.27 1.27)
				)
			)
		)
		(property "Value" ""
			(at 0 0 90)
			(layer "F.Fab")
			(effects
				(font
					(size 1.27 1.27)
				)
			)
		)
		(duplicate_pad_numbers_are_jumpers no)
		(fp_line
			(start 0.299974 -0.150114)
			(end 0.299974 0.150114)
			(stroke
				(width 0.1)
				(type default)
			)
			(layer "F.Fab")
		)
		(fp_line
			(start -0.299974 -0.150114)
			(end 0.299974 -0.150114)
			(stroke
				(width 0.1)
				(type default)
			)
			(layer "F.Fab")
		)
		(fp_line
			(start 0.299974 0.150114)
			(end -0.299974 0.150114)
			(stroke
				(width 0.1)
				(type default)
			)
			(layer "F.Fab")
		)
		(fp_line
			(start -0.299974 0.150114)
			(end -0.299974 -0.150114)
			(stroke
				(width 0.1)
				(type default)
			)
			(layer "F.Fab")
		)
		(pad "1" smd rect
			(at -0.2667 0 90)
			(size 0.3048 0.381)
			(layers "F.Cu" "F.Mask" "F.Paste")
			(net "P1V25_SERDES_VDDPLL_PEX1")
		)
		(pad "2" smd rect
			(at 0.2667 0 90)
			(size 0.3048 0.381)
			(layers "F.Cu" "F.Mask" "F.Paste")
			(net "GND")
		)
	)
	(footprint ""
		(layer "F.Cu")
		(at 80.019398 -146.190208 180)
		(property "Reference" "C12"
			(at 0 0 180)
			(layer "F.SilkS")
			(hide yes)
			(effects
				(font
					(size 1.27 1.27)
				)
			)
		)
		(property "Value" ""
			(at 0 0 180)
			(layer "F.Fab")
			(effects
				(font
					(size 1.27 1.27)
				)
			)
		)
		(duplicate_pad_numbers_are_jumpers no)
		(fp_line
			(start 0.299974 0.150114)
			(end -0.299974 0.150114)
			(stroke
				(width 0.1)
				(type default)
			)
			(layer "F.Fab")
		)
		(fp_line
			(start 0.299974 -0.150114)
			(end 0.299974 0.150114)
			(stroke
				(width 0.1)
				(type default)
			)
			(layer "F.Fab")
		)
		(fp_line
			(start -0.299974 0.150114)
			(end -0.299974 -0.150114)
			(stroke
				(width 0.1)
				(type default)
			)
			(layer "F.Fab")
		)
		(fp_line
			(start -0.299974 -0.150114)
			(end 0.299974 -0.150114)
			(stroke
				(width 0.1)
				(type default)
			)
			(layer "F.Fab")
		)
		(pad "1" smd rect
			(at -0.2667 0 180)
			(size 0.3048 0.381)
			(layers "F.Cu" "F.Mask" "F.Paste")
			(net "P5E_PEX0_STN0_TX_DN<10>")
		)
		(pad "2" smd rect
			(at 0.2667 0 180)
			(size 0.3048 0.381)
			(layers "F.Cu" "F.Mask" "F.Paste")
			(net "P5E_PEX0_STN0_TX_C_DN<10>")
		)
	)
	(footprint ""
		(layer "F.Cu")
		(at 137.047478 -21.37156)
		(property "Reference" "C3901"
			(at 0 0 0)
			(layer "F.SilkS")
			(hide yes)
			(effects
				(font
					(size 1.27 1.27)
				)
			)
		)
		(property "Value" ""
			(at 0 0 0)
			(layer "F.Fab")
			(effects
				(font
					(size 1.27 1.27)
				)
			)
		)
		(duplicate_pad_numbers_are_jumpers no)
		(fp_line
			(start -0.7874 -0.4064)
			(end 0.7874 -0.4064)
			(stroke
				(width 0.1524)
				(type default)
			)
			(layer "F.SilkS")
		)
		(fp_line
			(start -0.7874 0.4064)
			(end -0.7874 -0.4064)
			(stroke
				(width 0.1524)
				(type default)
			)
			(layer "F.SilkS")
		)
		(fp_line
			(start 0.7874 -0.4064)
			(end 0.7874 0.4064)
			(stroke
				(width 0.1524)
				(type default)
			)
			(layer "F.SilkS")
		)
		(fp_line
			(start 0.7874 0.4064)
			(end -0.7874 0.4064)
			(stroke
				(width 0.1524)
				(type default)
			)
			(layer "F.SilkS")
		)
		(fp_line
			(start -0.67945 -0.305054)
			(end -0.12065 -0.305054)
			(stroke
				(width 0.1)
				(type default)
			)
			(layer "F.Fab")
		)
		(fp_line
			(start -0.67945 0.3048)
			(end -0.67945 -0.305054)
			(stroke
				(width 0.1)
				(type default)
			)
			(layer "F.Fab")
		)
		(fp_line
			(start -0.12065 -0.305054)
			(end -0.12065 -0.2794)
			(stroke
				(width 0.1)
				(type default)
			)
			(layer "F.Fab")
		)
		(fp_line
			(start -0.12065 -0.2794)
			(end 0.12065 -0.2794)
			(stroke
				(width 0.1)
				(type default)
			)
			(layer "F.Fab")
		)
		(fp_line
			(start -0.12065 0.2794)
			(end -0.12065 0.3048)
			(stroke
				(width 0.1)
				(type default)
			)
			(layer "F.Fab")
		)
		(fp_line
			(start -0.12065 0.3048)
			(end -0.67945 0.3048)
			(stroke
				(width 0.1)
				(type default)
			)
			(layer "F.Fab")
		)
		(fp_line
			(start 0.120396 0.2794)
			(end -0.12065 0.2794)
			(stroke
				(width 0.1)
				(type default)
			)
			(layer "F.Fab")
		)
		(fp_line
			(start 0.120396 0.3048)
			(end 0.120396 0.2794)
			(stroke
				(width 0.1)
				(type default)
			)
			(layer "F.Fab")
		)
		(fp_line
			(start 0.12065 -0.3048)
			(end 0.67945 -0.3048)
			(stroke
				(width 0.1)
				(type default)
			)
			(layer "F.Fab")
		)
		(fp_line
			(start 0.12065 -0.2794)
			(end 0.12065 -0.3048)
			(stroke
				(width 0.1)
				(type default)
			)
			(layer "F.Fab")
		)
		(fp_line
			(start 0.67945 -0.3048)
			(end 0.67945 0.3048)
			(stroke
				(width 0.1)
				(type default)
			)
			(layer "F.Fab")
		)
		(fp_line
			(start 0.67945 0.3048)
			(end 0.120396 0.3048)
			(stroke
				(width 0.1)
				(type default)
			)
			(layer "F.Fab")
		)
		(pad "1" smd circle
			(at -0.40005 0)
			(size 0 0)
			(layers "F.Cu" "F.Mask" "F.Paste")
			(net "P12V_SSD4")
		)
		(pad "2" smd circle
			(at 0.40005 0)
			(size 0 0)
			(layers "F.Cu" "F.Mask" "F.Paste")
			(net "GND")
		)
	)
	(footprint ""
		(layer "F.Cu")
		(at 317.830708 -304.90795 90)
		(property "Reference" "R6720"
			(at 0 0 90)
			(layer "F.SilkS")
			(hide yes)
			(effects
				(font
					(size 1.27 1.27)
				)
			)
		)
		(property "Value" ""
			(at 0 0 90)
			(layer "F.Fab")
			(effects
				(font
					(size 1.27 1.27)
				)
			)
		)
		(duplicate_pad_numbers_are_jumpers no)
		(fp_line
			(start 0.7874 -0.4064)
			(end 0.7874 0.4064)
			(stroke
				(width 0.1524)
				(type default)
			)
			(layer "F.SilkS")
		)
		(fp_line
			(start -0.7874 -0.4064)
			(end 0.7874 -0.4064)
			(stroke
				(width 0.1524)
				(type default)
			)
			(layer "F.SilkS")
		)
		(fp_line
			(start 0.7874 0.4064)
			(end -0.7874 0.4064)
			(stroke
				(width 0.1524)
				(type default)
			)
			(layer "F.SilkS")
		)
		(fp_line
			(start -0.7874 0.4064)
			(end -0.7874 -0.4064)
			(stroke
				(width 0.1524)
				(type default)
			)
			(layer "F.SilkS")
		)
		(fp_line
			(start -0.12065 -0.305054)
			(end -0.12065 -0.2794)
			(stroke
				(width 0.1)
				(type default)
			)
			(layer "F.Fab")
		)
		(fp_line
			(start -0.67945 -0.305054)
			(end -0.12065 -0.305054)
			(stroke
				(width 0.1)
				(type default)
			)
			(layer "F.Fab")
		)
		(fp_line
			(start 0.67945 -0.3048)
			(end 0.67945 0.3048)
			(stroke
				(width 0.1)
				(type default)
			)
			(layer "F.Fab")
		)
		(fp_line
			(start 0.12065 -0.3048)
			(end 0.67945 -0.3048)
			(stroke
				(width 0.1)
				(type default)
			)
			(layer "F.Fab")
		)
		(fp_line
			(start 0.12065 -0.2794)
			(end 0.12065 -0.3048)
			(stroke
				(width 0.1)
				(type default)
			)
			(layer "F.Fab")
		)
		(fp_line
			(start -0.12065 -0.2794)
			(end 0.12065 -0.2794)
			(stroke
				(width 0.1)
				(type default)
			)
			(layer "F.Fab")
		)
		(fp_line
			(start 0.120396 0.2794)
			(end -0.12065 0.2794)
			(stroke
				(width 0.1)
				(type default)
			)
			(layer "F.Fab")
		)
		(fp_line
			(start -0.12065 0.2794)
			(end -0.12065 0.3048)
			(stroke
				(width 0.1)
				(type default)
			)
			(layer "F.Fab")
		)
		(fp_line
			(start 0.67945 0.3048)
			(end 0.120396 0.3048)
			(stroke
				(width 0.1)
				(type default)
			)
			(layer "F.Fab")
		)
		(fp_line
			(start 0.120396 0.3048)
			(end 0.120396 0.2794)
			(stroke
				(width 0.1)
				(type default)
			)
			(layer "F.Fab")
		)
		(fp_line
			(start -0.12065 0.3048)
			(end -0.67945 0.3048)
			(stroke
				(width 0.1)
				(type default)
			)
			(layer "F.Fab")
		)
		(fp_line
			(start -0.67945 0.3048)
			(end -0.67945 -0.305054)
			(stroke
				(width 0.1)
				(type default)
			)
			(layer "F.Fab")
		)
		(pad "1" smd circle
			(at -0.40005 0 90)
			(size 0 0)
			(layers "F.Cu" "F.Mask" "F.Paste")
			(net "SMB_PEX2_SLAVE1_SCL")
		)
		(pad "2" smd circle
			(at 0.40005 0 90)
			(size 0 0)
			(layers "F.Cu" "F.Mask" "F.Paste")
			(net "SMB_PEX2_R_SCL")
		)
	)
	(footprint ""
		(layer "F.Cu")
		(at 275.26869 -407.720292 90)
		(property "Reference" "R1813"
			(at 0 0 90)
			(layer "F.SilkS")
			(hide yes)
			(effects
				(font
					(size 1.27 1.27)
				)
			)
		)
		(property "Value" ""
			(at 0 0 90)
			(layer "F.Fab")
			(effects
				(font
					(size 1.27 1.27)
				)
			)
		)
		(duplicate_pad_numbers_are_jumpers no)
		(fp_line
			(start 0.7874 -0.4064)
			(end 0.7874 0.4064)
			(stroke
				(width 0.1524)
				(type default)
			)
			(layer "F.SilkS")
		)
		(fp_line
			(start -0.7874 -0.4064)
			(end 0.7874 -0.4064)
			(stroke
				(width 0.1524)
				(type default)
			)
			(layer "F.SilkS")
		)
		(fp_line
			(start 0.7874 0.4064)
			(end -0.7874 0.4064)
			(stroke
				(width 0.1524)
				(type default)
			)
			(layer "F.SilkS")
		)
		(fp_line
			(start -0.7874 0.4064)
			(end -0.7874 -0.4064)
			(stroke
				(width 0.1524)
				(type default)
			)
			(layer "F.SilkS")
		)
		(fp_line
			(start -0.12065 -0.305054)
			(end -0.12065 -0.2794)
			(stroke
				(width 0.1)
				(type default)
			)
			(layer "F.Fab")
		)
		(fp_line
			(start -0.67945 -0.305054)
			(end -0.12065 -0.305054)
			(stroke
				(width 0.1)
				(type default)
			)
			(layer "F.Fab")
		)
		(fp_line
			(start 0.67945 -0.3048)
			(end 0.67945 0.3048)
			(stroke
				(width 0.1)
				(type default)
			)
			(layer "F.Fab")
		)
		(fp_line
			(start 0.12065 -0.3048)
			(end 0.67945 -0.3048)
			(stroke
				(width 0.1)
				(type default)
			)
			(layer "F.Fab")
		)
		(fp_line
			(start 0.12065 -0.2794)
			(end 0.12065 -0.3048)
			(stroke
				(width 0.1)
				(type default)
			)
			(layer "F.Fab")
		)
		(fp_line
			(start -0.12065 -0.2794)
			(end 0.12065 -0.2794)
			(stroke
				(width 0.1)
				(type default)
			)
			(layer "F.Fab")
		)
		(fp_line
			(start 0.120396 0.2794)
			(end -0.12065 0.2794)
			(stroke
				(width 0.1)
				(type default)
			)
			(layer "F.Fab")
		)
		(fp_line
			(start -0.12065 0.2794)
			(end -0.12065 0.3048)
			(stroke
				(width 0.1)
				(type default)
			)
			(layer "F.Fab")
		)
		(fp_line
			(start 0.67945 0.3048)
			(end 0.120396 0.3048)
			(stroke
				(width 0.1)
				(type default)
			)
			(layer "F.Fab")
		)
		(fp_line
			(start 0.120396 0.3048)
			(end 0.120396 0.2794)
			(stroke
				(width 0.1)
				(type default)
			)
			(layer "F.Fab")
		)
		(fp_line
			(start -0.12065 0.3048)
			(end -0.67945 0.3048)
			(stroke
				(width 0.1)
				(type default)
			)
			(layer "F.Fab")
		)
		(fp_line
			(start -0.67945 0.3048)
			(end -0.67945 -0.305054)
			(stroke
				(width 0.1)
				(type default)
			)
			(layer "F.Fab")
		)
		(pad "1" smd circle
			(at -0.40005 0 90)
			(size 0 0)
			(layers "F.Cu" "F.Mask" "F.Paste")
			(net "P3V3_AUX")
		)
		(pad "2" smd circle
			(at 0.40005 0 90)
			(size 0 0)
			(layers "F.Cu" "F.Mask" "F.Paste")
			(net "RST_MB_BMC_BUF_N")
		)
	)
	(footprint ""
		(layer "F.Cu")
		(at 140.731748 -356.244906 90)
		(property "Reference" "C2262"
			(at 0 0 90)
			(layer "F.SilkS")
			(hide yes)
			(effects
				(font
					(size 1.27 1.27)
				)
			)
		)
		(property "Value" ""
			(at 0 0 90)
			(layer "F.Fab")
			(effects
				(font
					(size 1.27 1.27)
				)
			)
		)
		(duplicate_pad_numbers_are_jumpers no)
		(fp_line
			(start 0.299974 -0.150114)
			(end 0.299974 0.150114)
			(stroke
				(width 0.1)
				(type default)
			)
			(layer "F.Fab")
		)
		(fp_line
			(start -0.299974 -0.150114)
			(end 0.299974 -0.150114)
			(stroke
				(width 0.1)
				(type default)
			)
			(layer "F.Fab")
		)
		(fp_line
			(start 0.299974 0.150114)
			(end -0.299974 0.150114)
			(stroke
				(width 0.1)
				(type default)
			)
			(layer "F.Fab")
		)
		(fp_line
			(start -0.299974 0.150114)
			(end -0.299974 -0.150114)
			(stroke
				(width 0.1)
				(type default)
			)
			(layer "F.Fab")
		)
		(pad "1" smd rect
			(at -0.2667 0 90)
			(size 0.3048 0.381)
			(layers "F.Cu" "F.Mask" "F.Paste")
			(net "P5E_PEX1_STN5_TX_DN<86>")
		)
		(pad "2" smd rect
			(at 0.2667 0 90)
			(size 0.3048 0.381)
			(layers "F.Cu" "F.Mask" "F.Paste")
			(net "P5E_PEX1_STN5_TX_C_DN<86>")
		)
	)
)
